(kicad_pcb
	(version 20241229)
	(generator "pcbnew")
	(generator_version "9.0")
	(general
		(thickness 1.552)
		(legacy_teardrops no)
	)
	(paper "A4")
	(title_block
		(date "2023-07-25")
		(rev "1.1.4")
		(comment 9 "footprints 355-358 of 379")
	)
	(layers
		(0 "F.Cu" signal)
		(4 "In1.Cu" signal)
		(6 "In2.Cu" signal)
		(8 "In3.Cu" signal)
		(10 "In4.Cu" signal)
		(12 "In5.Cu" signal)
		(14 "In6.Cu" signal)
		(2 "B.Cu" signal)
		(9 "F.Adhes" user "F.Adhesive")
		(11 "B.Adhes" user "B.Adhesive")
		(13 "F.Paste" user)
		(15 "B.Paste" user)
		(5 "F.SilkS" user "F.Silkscreen")
		(7 "B.SilkS" user "B.Silkscreen")
		(1 "F.Mask" user)
		(3 "B.Mask" user)
		(17 "Dwgs.User" user "User.Drawings")
		(19 "Cmts.User" user "User.Comments")
		(21 "Eco1.User" user "User.Eco1")
		(23 "Eco2.User" user "User.Eco2")
		(25 "Edge.Cuts" user)
		(27 "Margin" user)
		(31 "F.CrtYd" user "F.Courtyard")
		(29 "B.CrtYd" user "B.Courtyard")
		(35 "F.Fab" user)
		(33 "B.Fab" user)
	)
	(footprint "antmicro-footprints:C_0402_1005Metric"
		(layer "B.Cu")
		(at 90.56 72.11 90)
		(descr "Capacitor SMD 0402")
		(tags "capacitor SMD 0402")
		(property "Reference" "C57"
			(at -1.03 -0.63 90)
			(layer "B.SilkS")
			(effects
				(font
					(size 0.65 0.65)
					(thickness 0.15)
				)
				(justify right bottom mirror)
			)
		)
		(property "Value" "C_1u_0402"
			(at 0 -1.4 90)
			(layer "B.Fab")
			(hide yes)
			(effects
				(font
					(size 0.7 0.7)
					(thickness 0.15)
				)
				(justify right bottom mirror)
			)
		)
		(property "Datasheet" "https://product.tdk.com/en/search/capacitor/ceramic/mlcc/info?part_no=C1005X6S1A105K050BC"
			(at 0 0 90)
			(layer "F.Fab")
			(hide yes)
			(effects
				(font
					(size 1.27 1.27)
					(thickness 0.15)
				)
			)
		)
		(property "Description" "SMD Multilayer Ceramic Capacitor, 1 µF, 10 V, 0402 [1005 Metric], ± 10%, X6S, C"
			(at 0 0 90)
			(layer "F.Fab")
			(hide yes)
			(effects
				(font
					(size 1.27 1.27)
					(thickness 0.15)
				)
			)
		)
		(property "Author" "Antmicro"
			(at 162.67 -18.45 0)
			(layer "B.Fab")
			(hide yes)
			(effects
				(font
					(size 1 1)
					(thickness 0.15)
				)
				(justify mirror)
			)
		)
		(property "Dielectric" ""
			(at 162.67 -18.45 0)
			(layer "B.Fab")
			(hide yes)
			(effects
				(font
					(size 1 1)
					(thickness 0.15)
				)
				(justify mirror)
			)
		)
		(property "License" "Apache-2.0"
			(at 162.67 -18.45 0)
			(layer "B.Fab")
			(hide yes)
			(effects
				(font
					(size 1 1)
					(thickness 0.15)
				)
				(justify mirror)
			)
		)
		(property "MPN" "C1005X6S1A105K050BC"
			(at 162.67 -18.45 0)
			(layer "B.Fab")
			(hide yes)
			(effects
				(font
					(size 1 1)
					(thickness 0.15)
				)
				(justify mirror)
			)
		)
		(property "Manufacturer" "TDK"
			(at 162.67 -18.45 0)
			(layer "B.Fab")
			(hide yes)
			(effects
				(font
					(size 1 1)
					(thickness 0.15)
				)
				(justify mirror)
			)
		)
		(property "Val" "1u"
			(at 162.67 -18.45 0)
			(layer "B.Fab")
			(hide yes)
			(effects
				(font
					(size 1 1)
					(thickness 0.15)
				)
				(justify mirror)
			)
		)
		(property "Voltage" ""
			(at 162.67 -18.45 0)
			(layer "B.Fab")
			(hide yes)
			(effects
				(font
					(size 1 1)
					(thickness 0.15)
				)
				(justify mirror)
			)
		)
		(sheetname "/SDI/")
		(sheetfile "sdi.kicad_sch")
		(attr smd)
		(fp_rect
			(start -0.925 0.47)
			(end 0.925 -0.47)
			(stroke
				(width 0.05)
				(type default)
			)
			(fill no)
			(layer "B.CrtYd")
		)
		(fp_line
			(start 0.504 -0.248)
			(end -0.494 -0.248)
			(stroke
				(width 0.15)
				(type solid)
			)
			(layer "B.Fab")
		)
		(fp_line
			(start -0.494 -0.248)
			(end -0.494 0.25)
			(stroke
				(width 0.15)
				(type solid)
			)
			(layer "B.Fab")
		)
		(fp_line
			(start 0.504 0.25)
			(end 0.504 -0.248)
			(stroke
				(width 0.15)
				(type solid)
			)
			(layer "B.Fab")
		)
		(fp_line
			(start -0.494 0.25)
			(end 0.504 0.25)
			(stroke
				(width 0.15)
				(type solid)
			)
			(layer "B.Fab")
		)
		(fp_text user "License: Apache-2.0"
			(at -0.939 -5.799 270)
			(layer "B.Fab")
			(effects
				(font
					(size 0.7 0.7)
					(thickness 0.15)
				)
				(justify left bottom mirror)
			)
		)
		(fp_text user "Author: Antmicro"
			(at -0.939 -3.399 270)
			(layer "B.Fab")
			(effects
				(font
					(size 0.7 0.7)
					(thickness 0.15)
				)
				(justify left bottom mirror)
			)
		)
		(fp_text user "${REFERENCE}"
			(at -0.939 -4.599 270)
			(layer "B.Fab")
			(effects
				(font
					(size 0.7 0.7)
					(thickness 0.15)
				)
				(justify left bottom mirror)
			)
		)
		(pad "1" smd roundrect
			(at -0.48 0 90)
			(size 0.59 0.64)
			(layers "B.Cu" "B.Mask" "B.Paste")
			(roundrect_rratio 0.25)
			(net 242 "Net-(U15B-VBG)")
			(pintype "passive")
		)
		(pad "2" smd roundrect
			(at 0.48 0 90)
			(size 0.59 0.64)
			(layers "B.Cu" "B.Mask" "B.Paste")
			(roundrect_rratio 0.25)
			(net 1 "GND")
			(pintype "passive")
		)
	)
	(footprint "antmicro-footprints:C_0402_1005Metric"
		(layer "B.Cu")
		(at 136.58 59.2 -90)
		(descr "Capacitor SMD 0402")
		(tags "capacitor SMD 0402")
		(property "Reference" "C3"
			(at -0.66 0.7 90)
			(layer "B.SilkS")
			(effects
				(font
					(size 0.65 0.65)
					(thickness 0.15)
				)
				(justify left bottom mirror)
			)
		)
		(property "Value" "C_100n_0402"
			(at 0 -1.4 90)
			(layer "B.Fab")
			(hide yes)
			(effects
				(font
					(size 0.7 0.7)
					(thickness 0.15)
				)
				(justify left bottom mirror)
			)
		)
		(property "Datasheet" "https://www.murata.com/products/productdetail?partno=GRM155R61H104KE14%23"
			(at 0 0 270)
			(layer "F.Fab")
			(hide yes)
			(effects
				(font
					(size 1.27 1.27)
					(thickness 0.15)
				)
			)
		)
		(property "Description" "SMD Multilayer Ceramic Capacitor, 0.1 µF, 50 V, 0402 [1005 Metric], ± 10%, X5R, GRM Series"
			(at 0 0 270)
			(layer "F.Fab")
			(hide yes)
			(effects
				(font
					(size 1.27 1.27)
					(thickness 0.15)
				)
			)
		)
		(property "Author" "Antmicro"
			(at 77.38 195.78 0)
			(layer "B.Fab")
			(hide yes)
			(effects
				(font
					(size 1 1)
					(thickness 0.15)
				)
				(justify mirror)
			)
		)
		(property "Dielectric" "X5R"
			(at 77.38 195.78 0)
			(layer "B.Fab")
			(hide yes)
			(effects
				(font
					(size 1 1)
					(thickness 0.15)
				)
				(justify mirror)
			)
		)
		(property "License" "Apache-2.0"
			(at 77.38 195.78 0)
			(layer "B.Fab")
			(hide yes)
			(effects
				(font
					(size 1 1)
					(thickness 0.15)
				)
				(justify mirror)
			)
		)
		(property "MPN" "GRM155R61H104KE14D"
			(at 77.38 195.78 0)
			(layer "B.Fab")
			(hide yes)
			(effects
				(font
					(size 1 1)
					(thickness 0.15)
				)
				(justify mirror)
			)
		)
		(property "Manufacturer" "Murata"
			(at 77.38 195.78 0)
			(layer "B.Fab")
			(hide yes)
			(effects
				(font
					(size 1 1)
					(thickness 0.15)
				)
				(justify mirror)
			)
		)
		(property "Val" "100n"
			(at 77.38 195.78 0)
			(layer "B.Fab")
			(hide yes)
			(effects
				(font
					(size 1 1)
					(thickness 0.15)
				)
				(justify mirror)
			)
		)
		(property "Voltage" "50V"
			(at 77.38 195.78 0)
			(layer "B.Fab")
			(hide yes)
			(effects
				(font
					(size 1 1)
					(thickness 0.15)
				)
				(justify mirror)
			)
		)
		(sheetname "/Power Supply/")
		(sheetfile "supply.kicad_sch")
		(attr smd)
		(fp_rect
			(start -0.925 0.47)
			(end 0.925 -0.47)
			(stroke
				(width 0.05)
				(type default)
			)
			(fill no)
			(layer "B.CrtYd")
		)
		(fp_line
			(start -0.494 0.25)
			(end 0.504 0.25)
			(stroke
				(width 0.15)
				(type solid)
			)
			(layer "B.Fab")
		)
		(fp_line
			(start 0.504 0.25)
			(end 0.504 -0.248)
			(stroke
				(width 0.15)
				(type solid)
			)
			(layer "B.Fab")
		)
		(fp_line
			(start -0.494 -0.248)
			(end -0.494 0.25)
			(stroke
				(width 0.15)
				(type solid)
			)
			(layer "B.Fab")
		)
		(fp_line
			(start 0.504 -0.248)
			(end -0.494 -0.248)
			(stroke
				(width 0.15)
				(type solid)
			)
			(layer "B.Fab")
		)
		(fp_text user "Author: Antmicro"
			(at -0.939 -3.399 90)
			(layer "B.Fab")
			(effects
				(font
					(size 0.7 0.7)
					(thickness 0.15)
				)
				(justify left bottom mirror)
			)
		)
		(fp_text user "License: Apache-2.0"
			(at -0.939 -5.799 90)
			(layer "B.Fab")
			(effects
				(font
					(size 0.7 0.7)
					(thickness 0.15)
				)
				(justify left bottom mirror)
			)
		)
		(fp_text user "${REFERENCE}"
			(at -0.939 -4.599 90)
			(layer "B.Fab")
			(effects
				(font
					(size 0.7 0.7)
					(thickness 0.15)
				)
				(justify left bottom mirror)
			)
		)
		(pad "1" smd roundrect
			(at -0.48 0 270)
			(size 0.59 0.64)
			(layers "B.Cu" "B.Mask" "B.Paste")
			(roundrect_rratio 0.25)
			(net 30 "Net-(U1-REF)")
			(pintype "passive")
		)
		(pad "2" smd roundrect
			(at 0.48 0 270)
			(size 0.59 0.64)
			(layers "B.Cu" "B.Mask" "B.Paste")
			(roundrect_rratio 0.25)
			(net 1 "GND")
			(pintype "passive")
		)
	)
	(footprint "antmicro-footprints:C_0201"
		(layer "B.Cu")
		(at 133.3 84.4 -135)
		(descr "Capacitor SMD 0201")
		(tags "capacitor SMD 0201")
		(property "Reference" "C37"
			(at -1.053589 -1.393 45)
			(layer "B.SilkS")
			(effects
				(font
					(size 0.65 0.65)
					(thickness 0.15)
				)
				(justify left bottom mirror)
			)
		)
		(property "Value" "C_100n_0201"
			(at 0 -1.399999 45)
			(layer "B.Fab")
			(hide yes)
			(effects
				(font
					(size 0.7 0.7)
					(thickness 0.15)
				)
				(justify left bottom mirror)
			)
		)
		(property "Datasheet" "https://www.yageo.com/en/Chart/Download/pdf/CC0201KRX6S5BB104"
			(at 0 0 225)
			(layer "F.Fab")
			(hide yes)
			(effects
				(font
					(size 1.27 1.27)
					(thickness 0.15)
				)
			)
		)
		(property "Description" "SMD Multilayer Ceramic Capacitor, 0.1 µF, 6.3 V, 0201 [0603 Metric], ± 10%, X6S, CC Series"
			(at 0 0 225)
			(layer "F.Fab")
			(hide yes)
			(effects
				(font
					(size 1.27 1.27)
					(thickness 0.15)
				)
			)
		)
		(property "Author" "Antmicro"
			(at 167.877522 238.337146 0)
			(layer "B.Fab")
			(hide yes)
			(effects
				(font
					(size 1 1)
					(thickness 0.15)
				)
				(justify mirror)
			)
		)
		(property "Dielectric" ""
			(at 167.877522 238.337146 0)
			(layer "B.Fab")
			(hide yes)
			(effects
				(font
					(size 1 1)
					(thickness 0.15)
				)
				(justify mirror)
			)
		)
		(property "License" "Apache-2.0"
			(at 167.877522 238.337146 0)
			(layer "B.Fab")
			(hide yes)
			(effects
				(font
					(size 1 1)
					(thickness 0.15)
				)
				(justify mirror)
			)
		)
		(property "MPN" "CC0201KRX6S5BB104"
			(at 167.877522 238.337146 0)
			(layer "B.Fab")
			(hide yes)
			(effects
				(font
					(size 1 1)
					(thickness 0.15)
				)
				(justify mirror)
			)
		)
		(property "Manufacturer" "YAGEO"
			(at 167.877522 238.337146 0)
			(layer "B.Fab")
			(hide yes)
			(effects
				(font
					(size 1 1)
					(thickness 0.15)
				)
				(justify mirror)
			)
		)
		(property "Val" "100n"
			(at 167.877522 238.337146 0)
			(layer "B.Fab")
			(hide yes)
			(effects
				(font
					(size 1 1)
					(thickness 0.15)
				)
				(justify mirror)
			)
		)
		(property "Voltage" ""
			(at 167.877522 238.337146 0)
			(layer "B.Fab")
			(hide yes)
			(effects
				(font
					(size 1 1)
					(thickness 0.15)
				)
				(justify mirror)
			)
		)
		(property "Public" "False"
			(at 0 0 225)
			(unlocked yes)
			(layer "B.Fab")
			(hide yes)
			(effects
				(font
					(size 1 1)
					(thickness 0.15)
				)
				(justify mirror)
			)
		)
		(sheetname "/DDR3/")
		(sheetfile "ddr3.kicad_sch")
		(attr smd)
		(fp_poly
			(pts
				(xy -0.7 0.35) (xy 0.7 0.35) (xy 0.7 -0.35) (xy -0.7 -0.35)
			)
			(stroke
				(width 0.05)
				(type default)
			)
			(fill no)
			(layer "B.CrtYd")
		)
		(fp_poly
			(pts
				(xy 0.3 -0.15) (xy -0.301 -0.15) (xy -0.301 0.149) (xy 0.3 0.149)
			)
			(stroke
				(width 0.15)
				(type solid)
			)
			(fill no)
			(layer "B.Fab")
		)
		(fp_text user "Author: Antmicro"
			(at -0.72 -5.400001 45)
			(layer "B.Fab")
			(effects
				(font
					(size 0.7 0.7)
					(thickness 0.15)
				)
				(justify left bottom mirror)
			)
		)
		(fp_text user "License: Apache-2.0"
			(at -0.72 -4.4 45)
			(layer "B.Fab")
			(effects
				(font
					(size 0.7 0.7)
					(thickness 0.15)
				)
				(justify left bottom mirror)
			)
		)
		(fp_text user "${REFERENCE}"
			(at -0.72 -3.4 45)
			(layer "B.Fab")
			(effects
				(font
					(size 0.7 0.7)
					(thickness 0.15)
				)
				(justify left bottom mirror)
			)
		)
		(pad "" smd roundrect
			(at -0.349 0.002 225)
			(size 0.318 0.36)
			(layers "B.Paste")
			(roundrect_rratio 0.25)
		)
		(pad "" smd roundrect
			(at 0.341 0.002 225)
			(size 0.318 0.36)
			(layers "B.Paste")
			(roundrect_rratio 0.25)
		)
		(pad "1" smd roundrect
			(at -0.321 0.002 225)
			(size 0.46 0.4)
			(layers "B.Cu" "B.Mask")
			(roundrect_rratio 0.25)
			(net 5 "Vref")
			(pintype "passive")
		)
		(pad "2" smd roundrect
			(at 0.32 0.002 225)
			(size 0.46 0.4)
			(layers "B.Cu" "B.Mask")
			(roundrect_rratio 0.25)
			(net 248 "+1V5")
			(pintype "passive")
		)
	)
	(footprint "antmicro-footprints:R_0201"
		(layer "B.Cu")
		(at 122.59 64.51 -90)
		(descr "Resistor SMD 0201")
		(tags "resistor SMD 0201")
		(property "Reference" "R43"
			(at -0.67 0.5 90)
			(layer "B.SilkS")
			(effects
				(font
					(size 0.65 0.65)
					(thickness 0.15)
				)
				(justify left bottom mirror)
			)
		)
		(property "Value" "R_100R_0201"
			(at 0 -1.25 90)
			(layer "B.Fab")
			(hide yes)
			(effects
				(font
					(size 0.7 0.7)
					(thickness 0.15)
				)
				(justify left bottom mirror)
			)
		)
		(property "Datasheet" "https://www.bourns.com/docs/product-datasheets/cr-a-as.pdf"
			(at 0 0 90)
			(layer "F.Fab")
			(hide yes)
			(effects
				(font
					(size 1.27 1.27)
					(thickness 0.15)
				)
			)
		)
		(property "Description" "SMD Chip Resistor, 100 ohm, ± 1%, 50 mW, 0201 [0603 Metric], Thick Film, Sulfur Resistant"
			(at 0 0 90)
			(layer "F.Fab")
			(hide yes)
			(effects
				(font
					(size 1.27 1.27)
					(thickness 0.15)
				)
			)
		)
		(property "Author" "Antmicro"
			(at 58.08 187.1 0)
			(layer "B.Fab")
			(hide yes)
			(effects
				(font
					(size 1 1)
					(thickness 0.15)
				)
				(justify mirror)
			)
		)
		(property "License" "Apache-2.0"
			(at 58.08 187.1 0)
			(layer "B.Fab")
			(hide yes)
			(effects
				(font
					(size 1 1)
					(thickness 0.15)
				)
				(justify mirror)
			)
		)
		(property "MPN" "CR0201AFW-1000GAS"
			(at 58.08 187.1 0)
			(layer "B.Fab")
			(hide yes)
			(effects
				(font
					(size 1 1)
					(thickness 0.15)
				)
				(justify mirror)
			)
		)
		(property "Manufacturer" "Bourns"
			(at 58.08 187.1 0)
			(layer "B.Fab")
			(hide yes)
			(effects
				(font
					(size 1 1)
					(thickness 0.15)
				)
				(justify mirror)
			)
		)
		(property "Tolerance" "1%"
			(at 58.08 187.1 0)
			(layer "B.Fab")
			(hide yes)
			(effects
				(font
					(size 1 1)
					(thickness 0.15)
				)
				(justify mirror)
			)
		)
		(property "Val" "100R"
			(at 58.08 187.1 0)
			(layer "B.Fab")
			(hide yes)
			(effects
				(font
					(size 1 1)
					(thickness 0.15)
				)
				(justify mirror)
			)
		)
		(sheetname "/DDR3/")
		(sheetfile "ddr3.kicad_sch")
		(attr smd)
		(fp_rect
			(start -0.7 0.35)
			(end 0.7 -0.35)
			(stroke
				(width 0.05)
				(type default)
			)
			(fill no)
			(layer "B.CrtYd")
		)
		(fp_rect
			(start -0.3 0.15)
			(end 0.298 -0.148)
			(stroke
				(width 0.15)
				(type solid)
			)
			(fill no)
			(layer "B.Fab")
		)
		(fp_text user "License: Apache-2.0"
			(at -0.71 -4.25 90)
			(layer "B.Fab")
			(effects
				(font
					(size 0.7 0.7)
					(thickness 0.15)
				)
				(justify left bottom mirror)
			)
		)
		(fp_text user "Author: Antmicro"
			(at -0.71 -5.25 90)
			(layer "B.Fab")
			(effects
				(font
					(size 0.7 0.7)
					(thickness 0.15)
				)
				(justify left bottom mirror)
			)
		)
		(fp_text user "${REFERENCE}"
			(at -0.71 -3.25 90)
			(layer "B.Fab")
			(effects
				(font
					(size 0.7 0.7)
					(thickness 0.15)
				)
				(justify left bottom mirror)
			)
		)
		(pad "" smd roundrect
			(at -0.346 0 270)
			(size 0.318 0.36)
			(layers "B.Paste")
			(roundrect_rratio 0.25)
		)
		(pad "" smd roundrect
			(at 0.344 0 270)
			(size 0.318 0.36)
			(layers "B.Paste")
			(roundrect_rratio 0.25)
		)
		(pad "1" smd roundrect
			(at -0.32 0 270)
			(size 0.46 0.4)
			(layers "B.Cu" "B.Mask")
			(roundrect_rratio 0.25)
			(net 142 "/DDR3/DDR3_CK_N")
			(pintype "passive")
		)
		(pad "2" smd roundrect
			(at 0.32 0 270)
			(size 0.46 0.4)
			(layers "B.Cu" "B.Mask")
			(roundrect_rratio 0.25)
			(net 143 "/DDR3/DDR3_CK_P")
			(pintype "passive")
		)
	)
)
